# T6G (Grand Teton) — schematic netlist excerpt (pin names and nets, part order shuffled) for the footprints in the layout excerpt that follows; sources: Cadence DE-HDL packaged netlist, KiCad conversion of 04192023_DAF0TMB3IC0_F0TG_MB_C_brd_V02_OCP.brd

R8167  Q_RES  1K 1% CHIP  pkg 0402LF  page 210 : A = P3V3_AUX ; B = PWRGD_PVDDCR_CPU0_P1_R
R6097  Q_RES  0 5% CHIP  pkg 0402LF  page 189 : A = MB0_P12V_STBY_PWRGD ; B = P5V_AUX_EN

(kicad_pcb
	(version 20260206)
	(generator "pcbnew")
	(generator_version "10.0")
	(general
		(thickness 1.6)
		(legacy_teardrops no)
	)
	(paper "A4")
	(title_block
		(title "04192023_DAF0TMB3IC0_F0TG_MB_C_brd_V02_OCP.brd")
		(comment 1 "Grand Teton / footprints 4668-4669 of 8354")
	)
	(layers
		(0 "F.Cu" signal "TOP")
		(4 "In1.Cu" signal "GND")
		(6 "In2.Cu" signal "IN1")
		(8 "In3.Cu" signal "GND1")
		(10 "In4.Cu" signal "IN2")
		(12 "In5.Cu" signal "GND2")
		(14 "In6.Cu" signal "IN3")
		(16 "In7.Cu" signal "GND3")
		(18 "In8.Cu" signal "VCC")
		(20 "In9.Cu" signal "VCC1")
		(22 "In10.Cu" signal "GND4")
		(24 "In11.Cu" signal "IN4")
		(26 "In12.Cu" signal "GND5")
		(28 "In13.Cu" signal "IN5")
		(30 "In14.Cu" signal "GND6")
		(32 "In15.Cu" signal "IN6")
		(34 "In16.Cu" signal "GND7")
		(2 "B.Cu" signal "BOTTOM")
		(9 "F.Adhes" user "F.Adhesive")
		(11 "B.Adhes" user "B.Adhesive")
		(13 "F.Paste" user "Package Geometry/Pastemask Top")
		(15 "B.Paste" user "Package Geometry/Pastemask Bottom")
		(5 "F.SilkS" user "Ref Des/Silkscreen Top")
		(7 "B.SilkS" user "Ref Des/Silkscreen Bottom")
		(1 "F.Mask" user "Board Geometry/Soldermask Top")
		(3 "B.Mask" user "Board Geometry/Soldermask Bottom")
		(17 "Dwgs.User" user "User.Drawings")
		(19 "Cmts.User" user "User.Comments")
		(21 "Eco1.User" user "User.Eco1")
		(23 "Eco2.User" user "User.Eco2")
		(25 "Edge.Cuts" user "Board Geometry/Outline")
		(27 "Margin" user)
		(31 "F.CrtYd" user "Package Geometry/Place Bound Top")
		(29 "B.CrtYd" user "Package Geometry/Place Bound Bottom")
		(35 "F.Fab" user "Ref Des/Assembly Top")
		(33 "B.Fab" user "Ref Des/Assembly Bottom")
	)
	(footprint ""
		(layer "F.Cu")
		(at 89.809828 -141.42466 90)
		(property "Reference" "R8167"
			(at 0 0 90)
			(layer "F.SilkS")
			(hide yes)
			(effects
				(font
					(size 1.27 1.27)
				)
			)
		)
		(property "Value" ""
			(at 0 0 90)
			(layer "F.Fab")
			(effects
				(font
					(size 1.27 1.27)
				)
			)
		)
		(duplicate_pad_numbers_are_jumpers no)
		(fp_line
			(start 0.7874 -0.4064)
			(end 0.7874 0.4064)
			(stroke
				(width 0.1524)
				(type default)
			)
			(layer "F.SilkS")
		)
		(fp_line
			(start -0.7874 -0.4064)
			(end 0.7874 -0.4064)
			(stroke
				(width 0.1524)
				(type default)
			)
			(layer "F.SilkS")
		)
		(fp_line
			(start 0.7874 0.4064)
			(end -0.7874 0.4064)
			(stroke
				(width 0.1524)
				(type default)
			)
			(layer "F.SilkS")
		)
		(fp_line
			(start -0.7874 0.4064)
			(end -0.7874 -0.4064)
			(stroke
				(width 0.1524)
				(type default)
			)
			(layer "F.SilkS")
		)
		(fp_line
			(start -0.12065 -0.305054)
			(end -0.12065 -0.2794)
			(stroke
				(width 0.1)
				(type default)
			)
			(layer "F.Fab")
		)
		(fp_line
			(start -0.67945 -0.305054)
			(end -0.12065 -0.305054)
			(stroke
				(width 0.1)
				(type default)
			)
			(layer "F.Fab")
		)
		(fp_line
			(start 0.67945 -0.3048)
			(end 0.67945 0.3048)
			(stroke
				(width 0.1)
				(type default)
			)
			(layer "F.Fab")
		)
		(fp_line
			(start 0.12065 -0.3048)
			(end 0.67945 -0.3048)
			(stroke
				(width 0.1)
				(type default)
			)
			(layer "F.Fab")
		)
		(fp_line
			(start 0.12065 -0.2794)
			(end 0.12065 -0.3048)
			(stroke
				(width 0.1)
				(type default)
			)
			(layer "F.Fab")
		)
		(fp_line
			(start -0.12065 -0.2794)
			(end 0.12065 -0.2794)
			(stroke
				(width 0.1)
				(type default)
			)
			(layer "F.Fab")
		)
		(fp_line
			(start 0.120396 0.2794)
			(end -0.12065 0.2794)
			(stroke
				(width 0.1)
				(type default)
			)
			(layer "F.Fab")
		)
		(fp_line
			(start -0.12065 0.2794)
			(end -0.12065 0.3048)
			(stroke
				(width 0.1)
				(type default)
			)
			(layer "F.Fab")
		)
		(fp_line
			(start 0.67945 0.3048)
			(end 0.120396 0.3048)
			(stroke
				(width 0.1)
				(type default)
			)
			(layer "F.Fab")
		)
		(fp_line
			(start 0.120396 0.3048)
			(end 0.120396 0.2794)
			(stroke
				(width 0.1)
				(type default)
			)
			(layer "F.Fab")
		)
		(fp_line
			(start -0.12065 0.3048)
			(end -0.67945 0.3048)
			(stroke
				(width 0.1)
				(type default)
			)
			(layer "F.Fab")
		)
		(fp_line
			(start -0.67945 0.3048)
			(end -0.67945 -0.305054)
			(stroke
				(width 0.1)
				(type default)
			)
			(layer "F.Fab")
		)
		(pad "1" smd circle
			(at -0.40005 0 90)
			(size 0 0)
			(layers "F.Cu" "F.Mask" "F.Paste")
			(net "P3V3_AUX")
		)
		(pad "2" smd circle
			(at 0.40005 0 90)
			(size 0 0)
			(layers "F.Cu" "F.Mask" "F.Paste")
			(net "PWRGD_PVDDCR_CPU0_P1_R")
		)
	)
	(footprint ""
		(layer "F.Cu")
		(at 409.478226 -137.854182)
		(property "Reference" "R6097"
			(at 0 0 0)
			(layer "F.SilkS")
			(hide yes)
			(effects
				(font
					(size 1.27 1.27)
				)
			)
		)
		(property "Value" ""
			(at 0 0 0)
			(layer "F.Fab")
			(effects
				(font
					(size 1.27 1.27)
				)
			)
		)
		(duplicate_pad_numbers_are_jumpers no)
		(fp_line
			(start -0.7874 -0.4064)
			(end 0.7874 -0.4064)
			(stroke
				(width 0.1524)
				(type default)
			)
			(layer "F.SilkS")
		)
		(fp_line
			(start -0.7874 0.4064)
			(end -0.7874 -0.4064)
			(stroke
				(width 0.1524)
				(type default)
			)
			(layer "F.SilkS")
		)
		(fp_line
			(start 0.7874 -0.4064)
			(end 0.7874 0.4064)
			(stroke
				(width 0.1524)
				(type default)
			)
			(layer "F.SilkS")
		)
		(fp_line
			(start 0.7874 0.4064)
			(end -0.7874 0.4064)
			(stroke
				(width 0.1524)
				(type default)
			)
			(layer "F.SilkS")
		)
		(fp_line
			(start -0.67945 -0.305054)
			(end -0.12065 -0.305054)
			(stroke
				(width 0.1)
				(type default)
			)
			(layer "F.Fab")
		)
		(fp_line
			(start -0.67945 0.3048)
			(end -0.67945 -0.305054)
			(stroke
				(width 0.1)
				(type default)
			)
			(layer "F.Fab")
		)
		(fp_line
			(start -0.12065 -0.305054)
			(end -0.12065 -0.2794)
			(stroke
				(width 0.1)
				(type default)
			)
			(layer "F.Fab")
		)
		(fp_line
			(start -0.12065 -0.2794)
			(end 0.12065 -0.2794)
			(stroke
				(width 0.1)
				(type default)
			)
			(layer "F.Fab")
		)
		(fp_line
			(start -0.12065 0.2794)
			(end -0.12065 0.3048)
			(stroke
				(width 0.1)
				(type default)
			)
			(layer "F.Fab")
		)
		(fp_line
			(start -0.12065 0.3048)
			(end -0.67945 0.3048)
			(stroke
				(width 0.1)
				(type default)
			)
			(layer "F.Fab")
		)
		(fp_line
			(start 0.120396 0.2794)
			(end -0.12065 0.2794)
			(stroke
				(width 0.1)
				(type default)
			)
			(layer "F.Fab")
		)
		(fp_line
			(start 0.120396 0.3048)
			(end 0.120396 0.2794)
			(stroke
				(width 0.1)
				(type default)
			)
			(layer "F.Fab")
		)
		(fp_line
			(start 0.12065 -0.3048)
			(end 0.67945 -0.3048)
			(stroke
				(width 0.1)
				(type default)
			)
			(layer "F.Fab")
		)
		(fp_line
			(start 0.12065 -0.2794)
			(end 0.12065 -0.3048)
			(stroke
				(width 0.1)
				(type default)
			)
			(layer "F.Fab")
		)
		(fp_line
			(start 0.67945 -0.3048)
			(end 0.67945 0.3048)
			(stroke
				(width 0.1)
				(type default)
			)
			(layer "F.Fab")
		)
		(fp_line
			(start 0.67945 0.3048)
			(end 0.120396 0.3048)
			(stroke
				(width 0.1)
				(type default)
			)
			(layer "F.Fab")
		)
		(pad "1" smd circle
			(at -0.40005 0)
			(size 0 0)
			(layers "F.Cu" "F.Mask" "F.Paste")
			(net "MB0_P12V_STBY_PWRGD")
		)
		(pad "2" smd circle
			(at 0.40005 0)
			(size 0 0)
			(layers "F.Cu" "F.Mask" "F.Paste")
			(net "P5V_AUX_EN")
		)
	)
)
